(kicad_pcb
	(version 20241229)
	(generator "pcbnew")
	(generator_version "9.0")
	(general
		(thickness 1.599998)
		(legacy_teardrops no)
	)
	(paper "A4")
	(title_block
		(title "Artix - Datacenter Secure Control Module (DC-SCM)")
		(date "2024-11-06")
		(rev "1.1.3")
		(comment 9 "footprint 110 of 544 (U14), pads 158-238 of 484")
	)
	(layers
		(0 "F.Cu" signal)
		(4 "In1.Cu" signal)
		(6 "In2.Cu" signal)
		(8 "In3.Cu" signal)
		(10 "In4.Cu" signal)
		(12 "In5.Cu" signal)
		(14 "In6.Cu" signal)
		(2 "B.Cu" signal)
		(9 "F.Adhes" user "F.Adhesive")
		(11 "B.Adhes" user "B.Adhesive")
		(13 "F.Paste" user)
		(15 "B.Paste" user)
		(5 "F.SilkS" user "F.Silkscreen")
		(7 "B.SilkS" user "B.Silkscreen")
		(1 "F.Mask" user)
		(3 "B.Mask" user)
		(17 "Dwgs.User" user "User.Drawings")
		(19 "Cmts.User" user "User.Comments")
		(21 "Eco1.User" user "User.Eco1")
		(23 "Eco2.User" user "User.Eco2")
		(25 "Edge.Cuts" user)
		(27 "Margin" user)
		(31 "F.CrtYd" user "F.Courtyard")
		(29 "B.CrtYd" user "B.Courtyard")
		(35 "F.Fab" user)
		(33 "B.Fab" user)
	)
	(footprint "antmicro-footprints:BGA-484_23x23mm_Layout22x22_P1mm_FGG484"
		(layer "F.Cu")
		(at 101.275 119.675 90)
		(property "Reference" "U14"
			(at 11.965 9.405 180)
			(layer "F.SilkS")
			(effects
				(font
					(size 0.7 0.7)
					(thickness 0.15)
				)
				(justify left bottom)
			)
		)
		(property "Value" "XC7A100T-FGG484"
			(at 0 13.1 90)
			(layer "F.Fab")
			(effects
				(font
					(size 0.7 0.7)
					(thickness 0.15)
				)
				(justify left bottom)
			)
		)
		(property "Datasheet" "https://docs.xilinx.com/v/u/en-US/ds181_Artix_7_Data_Sheet"
			(at 0 0 90)
			(layer "F.Fab")
			(hide yes)
			(effects
				(font
					(size 1.27 1.27)
					(thickness 0.15)
				)
			)
		)
		(property "Description" "Artix-7 Field Programmable Gate Array IC 210 324-LFBGA, CSPBGA"
			(at 0 0 90)
			(layer "F.Fab")
			(hide yes)
			(effects
				(font
					(size 1.27 1.27)
					(thickness 0.15)
				)
			)
		)
		(property "Author" "Antmicro"
			(at 220.95 18.4 0)
			(layer "F.Fab")
			(hide yes)
			(effects
				(font
					(size 1 1)
					(thickness 0.15)
				)
			)
		)
		(property "License" "Apache-2.0"
			(at 220.95 18.4 0)
			(layer "F.Fab")
			(hide yes)
			(effects
				(font
					(size 1 1)
					(thickness 0.15)
				)
			)
		)
		(property "MPN" "XC7A100T-FGG484"
			(at 220.95 18.4 0)
			(layer "F.Fab")
			(hide yes)
			(effects
				(font
					(size 1 1)
					(thickness 0.15)
				)
			)
		)
		(property "Manufacturer" "AMD-Xilinx"
			(at 220.95 18.4 0)
			(layer "F.Fab")
			(hide yes)
			(effects
				(font
					(size 1 1)
					(thickness 0.15)
				)
			)
		)
		(sheetname "/FPGA power supply/")
		(sheetfile "fpga-power-supply.kicad_sch")
		(solder_mask_margin 0.05)
		(attr smd)
		(pad "F4" smd circle
			(at -7.5 -5.5 90)
			(size 0.5 0.5)
			(layers "F.Cu" "F.Mask" "F.Paste")
			(net 598 "unconnected-(U14C-IO_0_35-PadF4)")
			(pinfunction "IO_0_35")
			(pintype "bidirectional+no_connect")
		)
		(pad "F5" smd circle
			(at -6.5 -5.5 90)
			(size 0.5 0.5)
			(layers "F.Cu" "F.Mask" "F.Paste")
			(net 1 "GND")
			(pinfunction "GND")
			(pintype "passive")
		)
		(pad "F6" smd circle
			(at -5.5 -5.5 90)
			(size 0.5 0.5)
			(layers "F.Cu" "F.Mask" "F.Paste")
			(net 379 "PCIE_BMC_CLK_100_P")
			(pinfunction "MGTREFCLK0P_216")
			(pintype "bidirectional")
		)
		(pad "F7" smd circle
			(at -4.5 -5.5 90)
			(size 0.5 0.5)
			(layers "F.Cu" "F.Mask" "F.Paste")
			(net 6 "VCC1V0")
			(pinfunction "MGTAVCC")
			(pintype "passive")
		)
		(pad "F8" smd circle
			(at -3.5 -5.5 90)
			(size 0.5 0.5)
			(layers "F.Cu" "F.Mask" "F.Paste")
			(net 533 "Net-(U14E-MGTRREF_216)")
			(pinfunction "MGTRREF_216")
			(pintype "passive")
		)
		(pad "F9" smd circle
			(at -2.5 -5.5 90)
			(size 0.5 0.5)
			(layers "F.Cu" "F.Mask" "F.Paste")
			(net 6 "VCC1V0")
			(pinfunction "MGTAVCC")
			(pintype "passive")
		)
		(pad "F10" smd circle
			(at -1.5 -5.5 90)
			(size 0.5 0.5)
			(layers "F.Cu" "F.Mask" "F.Paste")
			(net 599 "unconnected-(U14E-MGTREFCLK1P_216-PadF10)")
			(pinfunction "MGTREFCLK1P_216")
			(pintype "bidirectional+no_connect")
		)
		(pad "F11" smd circle
			(at -0.5 -5.5 90)
			(size 0.5 0.5)
			(layers "F.Cu" "F.Mask" "F.Paste")
			(net 1 "GND")
			(pinfunction "GND")
			(pintype "passive")
		)
		(pad "F12" smd circle
			(at 0.498 -5.5 90)
			(size 0.5 0.5)
			(layers "F.Cu" "F.Mask" "F.Paste")
			(net 2 "VCC3V3")
			(pinfunction "VCCO_0")
			(pintype "power_in")
		)
		(pad "F13" smd circle
			(at 1.499 -5.5 90)
			(size 0.5 0.5)
			(layers "F.Cu" "F.Mask" "F.Paste")
			(net 20 "I2C[7]_SCL")
			(pinfunction "IO_L1P_T0_16")
			(pintype "bidirectional")
		)
		(pad "F14" smd circle
			(at 2.499 -5.5 90)
			(size 0.5 0.5)
			(layers "F.Cu" "F.Mask" "F.Paste")
			(net 600 "unconnected-(U14B-IO_L1N_T0_16-PadF14)")
			(pinfunction "IO_L1N_T0_16")
			(pintype "bidirectional+no_connect")
		)
		(pad "F15" smd circle
			(at 3.499 -5.5 90)
			(size 0.5 0.5)
			(layers "F.Cu" "F.Mask" "F.Paste")
			(net 601 "unconnected-(U14B-IO_0_16-PadF15)")
			(pinfunction "IO_0_16")
			(pintype "bidirectional+no_connect")
		)
		(pad "F16" smd circle
			(at 4.498 -5.5 90)
			(size 0.5 0.5)
			(layers "F.Cu" "F.Mask" "F.Paste")
			(net 602 "unconnected-(U14B-IO_L2P_T0_16-PadF16)")
			(pinfunction "IO_L2P_T0_16")
			(pintype "bidirectional+no_connect")
		)
		(pad "F17" smd circle
			(at 5.499 -5.5 90)
			(size 0.5 0.5)
			(layers "F.Cu" "F.Mask" "F.Paste")
			(net 1 "GND")
			(pinfunction "GND")
			(pintype "passive")
		)
		(pad "F18" smd circle
			(at 6.499 -5.5 90)
			(size 0.5 0.5)
			(layers "F.Cu" "F.Mask" "F.Paste")
			(net 174 "I3C[3]_SDA_3V3")
			(pinfunction "IO_L15P_T2_DQS_16")
			(pintype "bidirectional")
		)
		(pad "F19" smd circle
			(at 7.499 -5.5 90)
			(size 0.5 0.5)
			(layers "F.Cu" "F.Mask" "F.Paste")
			(net 172 "I3C[2]_SDA_3V3")
			(pinfunction "IO_L18P_T2_16")
			(pintype "bidirectional")
		)
		(pad "F20" smd circle
			(at 8.499 -5.5 90)
			(size 0.5 0.5)
			(layers "F.Cu" "F.Mask" "F.Paste")
			(net 170 "I3C[1]_SDA_3V3")
			(pinfunction "IO_L18N_T2_16")
			(pintype "bidirectional")
		)
		(pad "F21" smd circle
			(at 9.499 -5.5 90)
			(size 0.5 0.5)
			(layers "F.Cu" "F.Mask" "F.Paste")
			(net 565 "ROT_GPIO2")
			(pinfunction "IO_25_16")
			(pintype "bidirectional")
		)
		(pad "F22" smd circle
			(at 10.499 -5.5 90)
			(size 0.5 0.5)
			(layers "F.Cu" "F.Mask" "F.Paste")
			(net 2 "VCC3V3")
			(pinfunction "VCCO_16")
			(pintype "passive")
		)
		(pad "G1" smd circle
			(at -10.5 -4.5 90)
			(size 0.5 0.5)
			(layers "F.Cu" "F.Mask" "F.Paste")
			(net 191 "DDR3_RESET")
			(pinfunction "IO_L5P_T0_AD13P_35")
			(pintype "bidirectional")
		)
		(pad "G2" smd circle
			(at -9.5 -4.5 90)
			(size 0.5 0.5)
			(layers "F.Cu" "F.Mask" "F.Paste")
			(net 194 "DDR3_DQ0")
			(pinfunction "IO_L8N_T1_AD14N_35")
			(pintype "bidirectional")
		)
		(pad "G3" smd circle
			(at -8.5 -4.5 90)
			(size 0.5 0.5)
			(layers "F.Cu" "F.Mask" "F.Paste")
			(net 176 "DDR3_DM0")
			(pinfunction "IO_L11N_T1_SRCC_35")
			(pintype "bidirectional")
		)
		(pad "G4" smd circle
			(at -7.5 -4.5 90)
			(size 0.5 0.5)
			(layers "F.Cu" "F.Mask" "F.Paste")
			(net 603 "unconnected-(U14C-IO_L12N_T1_MRCC_35-PadG4)")
			(pinfunction "IO_L12N_T1_MRCC_35")
			(pintype "bidirectional+no_connect")
		)
		(pad "G5" smd circle
			(at -6.5 -4.5 90)
			(size 0.5 0.5)
			(layers "F.Cu" "F.Mask" "F.Paste")
			(net 1 "GND")
			(pinfunction "GND")
			(pintype "passive")
		)
		(pad "G6" smd circle
			(at -5.5 -4.5 90)
			(size 0.5 0.5)
			(layers "F.Cu" "F.Mask" "F.Paste")
			(net 1 "GND")
			(pinfunction "GND")
			(pintype "passive")
		)
		(pad "G7" smd circle
			(at -4.5 -4.5 90)
			(size 0.5 0.5)
			(layers "F.Cu" "F.Mask" "F.Paste")
			(net 1 "GND")
			(pinfunction "GND")
			(pintype "passive")
		)
		(pad "G8" smd circle
			(at -3.5 -4.5 90)
			(size 0.5 0.5)
			(layers "F.Cu" "F.Mask" "F.Paste")
			(net 1 "GND")
			(pinfunction "GND")
			(pintype "passive")
		)
		(pad "G9" smd circle
			(at -2.5 -4.5 90)
			(size 0.5 0.5)
			(layers "F.Cu" "F.Mask" "F.Paste")
			(net 1 "GND")
			(pinfunction "GND")
			(pintype "passive")
		)
		(pad "G10" smd circle
			(at -1.5 -4.5 90)
			(size 0.5 0.5)
			(layers "F.Cu" "F.Mask" "F.Paste")
			(net 1 "GND")
			(pinfunction "GND")
			(pintype "passive")
		)
		(pad "G11" smd circle
			(at -0.5 -4.5 90)
			(size 0.5 0.5)
			(layers "F.Cu" "F.Mask" "F.Paste")
			(net 220 "DONE")
			(pinfunction "DONE_0")
			(pintype "bidirectional")
		)
		(pad "G12" smd circle
			(at 0.498 -4.5 90)
			(size 0.5 0.5)
			(layers "F.Cu" "F.Mask" "F.Paste")
			(net 1 "GND")
			(pinfunction "GND")
			(pintype "passive")
		)
		(pad "G13" smd circle
			(at 1.499 -4.5 90)
			(size 0.5 0.5)
			(layers "F.Cu" "F.Mask" "F.Paste")
			(net 29 "I2C[6]_SDA")
			(pinfunction "IO_L1N_T0_AD0N_15")
			(pintype "bidirectional")
		)
		(pad "G14" smd circle
			(at 2.499 -4.5 90)
			(size 0.5 0.5)
			(layers "F.Cu" "F.Mask" "F.Paste")
			(net 1 "GND")
			(pinfunction "GND")
			(pintype "passive")
		)
		(pad "G15" smd circle
			(at 3.499 -4.5 90)
			(size 0.5 0.5)
			(layers "F.Cu" "F.Mask" "F.Paste")
			(net 69 "ESPI_CS1_N")
			(pinfunction "IO_L2P_T0_AD8P_15")
			(pintype "bidirectional")
		)
		(pad "G16" smd circle
			(at 4.498 -4.5 90)
			(size 0.5 0.5)
			(layers "F.Cu" "F.Mask" "F.Paste")
			(net 604 "unconnected-(U14B-IO_L2N_T0_AD8N_15-PadG16)")
			(pinfunction "IO_L2N_T0_AD8N_15")
			(pintype "bidirectional+no_connect")
		)
		(pad "G17" smd circle
			(at 5.499 -4.5 90)
			(size 0.5 0.5)
			(layers "F.Cu" "F.Mask" "F.Paste")
			(net 592 "TPM_PIRQ#")
			(pinfunction "IO_L4P_T0_15")
			(pintype "bidirectional")
		)
		(pad "G18" smd circle
			(at 6.499 -4.5 90)
			(size 0.5 0.5)
			(layers "F.Cu" "F.Mask" "F.Paste")
			(net 589 "TPM_PP")
			(pinfunction "IO_L4N_T0_15")
			(pintype "bidirectional")
		)
		(pad "G19" smd circle
			(at 7.499 -4.5 90)
			(size 0.5 0.5)
			(layers "F.Cu" "F.Mask" "F.Paste")
			(net 2 "VCC3V3")
			(pinfunction "VCCO_15")
			(pintype "power_in")
		)
		(pad "G20" smd circle
			(at 8.499 -4.5 90)
			(size 0.5 0.5)
			(layers "F.Cu" "F.Mask" "F.Paste")
			(net 425 "RGMII_TXD0")
			(pinfunction "IO_L8N_T1_AD10N_15")
			(pintype "bidirectional")
		)
		(pad "G21" smd circle
			(at 9.499 -4.5 90)
			(size 0.5 0.5)
			(layers "F.Cu" "F.Mask" "F.Paste")
			(net 605 "unconnected-(U14B-IO_L24P_T3_16-PadG21)")
			(pinfunction "IO_L24P_T3_16")
			(pintype "bidirectional+no_connect")
		)
		(pad "G22" smd circle
			(at 10.499 -4.5 90)
			(size 0.5 0.5)
			(layers "F.Cu" "F.Mask" "F.Paste")
			(net 566 "ROT_GPIO1")
			(pinfunction "IO_L24N_T3_16")
			(pintype "bidirectional")
		)
		(pad "H1" smd circle
			(at -10.5 -3.5 90)
			(size 0.5 0.5)
			(layers "F.Cu" "F.Mask" "F.Paste")
			(net 1 "GND")
			(pinfunction "GND")
			(pintype "passive")
		)
		(pad "H2" smd circle
			(at -9.5 -3.5 90)
			(size 0.5 0.5)
			(layers "F.Cu" "F.Mask" "F.Paste")
			(net 192 "DDR3_DQ6")
			(pinfunction "IO_L8P_T1_AD14P_35")
			(pintype "bidirectional")
		)
		(pad "H3" smd circle
			(at -8.5 -3.5 90)
			(size 0.5 0.5)
			(layers "F.Cu" "F.Mask" "F.Paste")
			(net 186 "DDR3_DQ5")
			(pinfunction "IO_L11P_T1_SRCC_35")
			(pintype "bidirectional")
		)
		(pad "H4" smd circle
			(at -7.5 -3.5 90)
			(size 0.5 0.5)
			(layers "F.Cu" "F.Mask" "F.Paste")
			(net 188 "DDR3_DQ1")
			(pinfunction "IO_L12P_T1_MRCC_35")
			(pintype "bidirectional")
		)
		(pad "H5" smd circle
			(at -6.5 -3.5 90)
			(size 0.5 0.5)
			(layers "F.Cu" "F.Mask" "F.Paste")
			(net 187 "DDR3_DQ2")
			(pinfunction "IO_L10N_T1_AD15N_35")
			(pintype "bidirectional")
		)
		(pad "H6" smd circle
			(at -5.5 -3.5 90)
			(size 0.5 0.5)
			(layers "F.Cu" "F.Mask" "F.Paste")
			(net 3 "VCC1V35")
			(pinfunction "VCCO_35")
			(pintype "passive")
		)
		(pad "H7" smd circle
			(at -4.5 -3.5 90)
			(size 0.5 0.5)
			(layers "F.Cu" "F.Mask" "F.Paste")
			(net 1 "GND")
			(pinfunction "GND")
			(pintype "passive")
		)
		(pad "H8" smd circle
			(at -3.5 -3.5 90)
			(size 0.5 0.5)
			(layers "F.Cu" "F.Mask" "F.Paste")
			(net 6 "VCC1V0")
			(pinfunction "VCCINT")
			(pintype "power_in")
		)
		(pad "H9" smd circle
			(at -2.5 -3.5 90)
			(size 0.5 0.5)
			(layers "F.Cu" "F.Mask" "F.Paste")
			(net 1 "GND")
			(pinfunction "GND")
			(pintype "passive")
		)
		(pad "H10" smd circle
			(at -1.5 -3.5 90)
			(size 0.5 0.5)
			(layers "F.Cu" "F.Mask" "F.Paste")
			(net 6 "VCC1V0")
			(pinfunction "VCCINT")
			(pintype "passive")
		)
		(pad "H11" smd circle
			(at -0.5 -3.5 90)
			(size 0.5 0.5)
			(layers "F.Cu" "F.Mask" "F.Paste")
			(net 1 "GND")
			(pinfunction "GND")
			(pintype "passive")
		)
		(pad "H12" smd circle
			(at 0.498 -3.5 90)
			(size 0.5 0.5)
			(layers "F.Cu" "F.Mask" "F.Paste")
			(net 5 "VCC1V8")
			(pinfunction "VCCAUX")
			(pintype "power_in")
		)
		(pad "H13" smd circle
			(at 1.499 -3.5 90)
			(size 0.5 0.5)
			(layers "F.Cu" "F.Mask" "F.Paste")
			(net 28 "I2C[6]_SCL")
			(pinfunction "IO_L1P_T0_AD0P_15")
			(pintype "bidirectional")
		)
		(pad "H14" smd circle
			(at 2.499 -3.5 90)
			(size 0.5 0.5)
			(layers "F.Cu" "F.Mask" "F.Paste")
			(net 606 "unconnected-(U14B-IO_L3N_T0_DQS_AD1N_15-PadH14)")
			(pinfunction "IO_L3N_T0_DQS_AD1N_15")
			(pintype "bidirectional+no_connect")
		)
		(pad "H15" smd circle
			(at 3.499 -3.5 90)
			(size 0.5 0.5)
			(layers "F.Cu" "F.Mask" "F.Paste")
			(net 607 "unconnected-(U14B-IO_L5N_T0_AD9N_15-PadH15)")
			(pinfunction "IO_L5N_T0_AD9N_15")
			(pintype "bidirectional+no_connect")
		)
		(pad "H16" smd circle
			(at 4.498 -3.5 90)
			(size 0.5 0.5)
			(layers "F.Cu" "F.Mask" "F.Paste")
			(net 2 "VCC3V3")
			(pinfunction "VCCO_15")
			(pintype "passive")
		)
		(pad "H17" smd circle
			(at 5.499 -3.5 90)
			(size 0.5 0.5)
			(layers "F.Cu" "F.Mask" "F.Paste")
			(net 608 "unconnected-(U14B-IO_L6P_T0_15-PadH17)")
			(pinfunction "IO_L6P_T0_15")
			(pintype "bidirectional+no_connect")
		)
		(pad "H18" smd circle
			(at 6.499 -3.5 90)
			(size 0.5 0.5)
			(layers "F.Cu" "F.Mask" "F.Paste")
			(net 63 "ESPI_ALERT_N")
			(pinfunction "IO_L6N_T0_VREF_15")
			(pintype "bidirectional")
		)
		(pad "H19" smd circle
			(at 7.499 -3.5 90)
			(size 0.5 0.5)
			(layers "F.Cu" "F.Mask" "F.Paste")
			(net 413 "RGMII_REF_CLK")
			(pinfunction "IO_L12N_T1_MRCC_15")
			(pintype "bidirectional")
		)
		(pad "H20" smd circle
			(at 8.499 -3.5 90)
			(size 0.5 0.5)
			(layers "F.Cu" "F.Mask" "F.Paste")
			(net 424 "RGMII_TXD1")
			(pinfunction "IO_L8P_T1_AD10P_15")
			(pintype "bidirectional")
		)
		(pad "H21" smd circle
			(at 9.499 -3.5 90)
			(size 0.5 0.5)
			(layers "F.Cu" "F.Mask" "F.Paste")
			(net 1 "GND")
			(pinfunction "GND")
			(pintype "passive")
		)
		(pad "H22" smd circle
			(at 10.499 -3.5 90)
			(size 0.5 0.5)
			(layers "F.Cu" "F.Mask" "F.Paste")
			(net 423 "RGMII_TXD2")
			(pinfunction "IO_L7N_T1_AD2N_15")
			(pintype "bidirectional")
		)
		(pad "J1" smd circle
			(at -10.5 -2.5 90)
			(size 0.5 0.5)
			(layers "F.Cu" "F.Mask" "F.Paste")
			(net 190 "DDR3_DQ3")
			(pinfunction "IO_L7N_T1_AD6N_35")
			(pintype "bidirectional")
		)
		(pad "J2" smd circle
			(at -9.5 -2.5 90)
			(size 0.5 0.5)
			(layers "F.Cu" "F.Mask" "F.Paste")
			(net 476 "DDR3_DQS0_N")
			(pinfunction "IO_L9N_T1_DQS_AD7N_35")
			(pintype "bidirectional")
		)
		(pad "J3" smd circle
			(at -8.5 -2.5 90)
			(size 0.5 0.5)
			(layers "F.Cu" "F.Mask" "F.Paste")
			(net 3 "VCC1V35")
			(pinfunction "VCCO_35")
			(pintype "passive")
		)
		(pad "J4" smd circle
			(at -7.5 -2.5 90)
			(size 0.5 0.5)
			(layers "F.Cu" "F.Mask" "F.Paste")
			(net 162 "DDR3_RAS")
			(pinfunction "IO_L13N_T2_MRCC_35")
			(pintype "bidirectional")
		)
		(pad "J5" smd circle
			(at -6.5 -2.5 90)
			(size 0.5 0.5)
			(layers "F.Cu" "F.Mask" "F.Paste")
			(net 185 "DDR3_DQ7")
			(pinfunction "IO_L10P_T1_AD15P_35")
			(pintype "bidirectional")
		)
		(pad "J6" smd circle
			(at -5.5 -2.5 90)
			(size 0.5 0.5)
			(layers "F.Cu" "F.Mask" "F.Paste")
			(net 160 "DDR3_CKE")
			(pinfunction "IO_L17N_T2_35")
			(pintype "bidirectional")
		)
		(pad "J7" smd circle
			(at -4.5 -2.5 90)
			(size 0.5 0.5)
			(layers "F.Cu" "F.Mask" "F.Paste")
			(net 6 "VCC1V0")
			(pinfunction "VCCINT")
			(pintype "passive")
		)
		(pad "J8" smd circle
			(at -3.5 -2.5 90)
			(size 0.5 0.5)
			(layers "F.Cu" "F.Mask" "F.Paste")
			(net 1 "GND")
			(pinfunction "GND")
			(pintype "passive")
		)
		(pad "J9" smd circle
			(at -2.5 -2.5 90)
			(size 0.5 0.5)
			(layers "F.Cu" "F.Mask" "F.Paste")
			(net 6 "VCC1V0")
			(pinfunction "VCCINT")
			(pintype "passive")
		)
		(pad "J10" smd circle
			(at -1.5 -2.5 90)
			(size 0.5 0.5)
			(layers "F.Cu" "F.Mask" "F.Paste")
			(net 1 "GND")
			(pinfunction "GND")
			(pintype "passive")
		)
		(pad "J11" smd circle
			(at -0.5 -2.5 90)
			(size 0.5 0.5)
			(layers "F.Cu" "F.Mask" "F.Paste")
			(net 6 "VCC1V0")
			(pinfunction "VCCBRAM")
			(pintype "power_in")
		)
		(pad "J12" smd circle
			(at 0.498 -2.5 90)
			(size 0.5 0.5)
			(layers "F.Cu" "F.Mask" "F.Paste")
			(net 1 "GND")
			(pinfunction "GND")
			(pintype "passive")
		)
		(pad "J13" smd circle
			(at 1.499 -2.5 90)
			(size 0.5 0.5)
			(layers "F.Cu" "F.Mask" "F.Paste")
			(net 2 "VCC3V3")
			(pinfunction "VCCO_15")
			(pintype "passive")
		)
		(pad "J14" smd circle
			(at 2.499 -2.5 90)
			(size 0.5 0.5)
			(layers "F.Cu" "F.Mask" "F.Paste")
			(net 25 "I2C[2]_SDA")
			(pinfunction "IO_L3P_T0_DQS_AD1P_15")
			(pintype "bidirectional")
		)
		(pad "J15" smd circle
			(at 3.499 -2.5 90)
			(size 0.5 0.5)
			(layers "F.Cu" "F.Mask" "F.Paste")
			(net 32 "I2C[0]_SDA")
			(pinfunction "IO_L5P_T0_AD9P_15")
			(pintype "bidirectional")
		)
		(pad "J16" smd circle
			(at 4.498 -2.5 90)
			(size 0.5 0.5)
			(layers "F.Cu" "F.Mask" "F.Paste")
			(net 31 "I2C[0]_SCL")
			(pinfunction "IO_0_15")
			(pintype "bidirectional")
		)
		(pad "J17" smd circle
			(at 5.499 -2.5 90)
			(size 0.5 0.5)
			(layers "F.Cu" "F.Mask" "F.Paste")
			(net 609 "unconnected-(U14B-IO_L21N_T3_DQS_A18_15-PadJ17)")
			(pinfunction "IO_L21N_T3_DQS_A18_15")
			(pintype "bidirectional+no_connect")
		)
		(pad "J18" smd circle
			(at 6.499 -2.5 90)
			(size 0.5 0.5)
			(layers "F.Cu" "F.Mask" "F.Paste")
			(net 1 "GND")
			(pinfunction "GND")
			(pintype "passive")
		)
	)
)
